(kicad_pcb
	(version 20260206)
	(generator "pcbnew")
	(generator_version "10.0")
	(general
		(thickness 1.6)
		(legacy_teardrops no)
	)
	(paper "A4")
	(title_block
		(title "01162023_DA0F0TEBIF0_F0T_Expander_BD_F_brd_V02_OCP.brd")
		(comment 1 "Grand Teton / footprints 5973-5978 of 9728")
	)
	(layers
		(0 "F.Cu" signal "TOP")
		(4 "In1.Cu" signal "GND")
		(6 "In2.Cu" signal "VCC")
		(8 "In3.Cu" signal "VCC1")
		(10 "In4.Cu" signal "GND1")
		(12 "In5.Cu" signal "IN1")
		(14 "In6.Cu" signal "GND2")
		(16 "In7.Cu" signal "IN2")
		(18 "In8.Cu" signal "GND3")
		(20 "In9.Cu" signal "IN3")
		(22 "In10.Cu" signal "GND4")
		(24 "In11.Cu" signal "IN4")
		(26 "In12.Cu" signal "GND5")
		(28 "In13.Cu" signal "IN5")
		(30 "In14.Cu" signal "GND6")
		(32 "In15.Cu" signal "IN6")
		(34 "In16.Cu" signal "GND7")
		(2 "B.Cu" signal "BOTTOM")
		(9 "F.Adhes" user "F.Adhesive")
		(11 "B.Adhes" user "B.Adhesive")
		(13 "F.Paste" user "Package Geometry/Pastemask Top")
		(15 "B.Paste" user "Package Geometry/Pastemask Bottom")
		(5 "F.SilkS" user "Ref Des/Silkscreen Top")
		(7 "B.SilkS" user "Ref Des/Silkscreen Bottom")
		(1 "F.Mask" user "Board Geometry/Soldermask Top")
		(3 "B.Mask" user "Board Geometry/Soldermask Bottom")
		(17 "Dwgs.User" user "User.Drawings")
		(19 "Cmts.User" user "User.Comments")
		(21 "Eco1.User" user "User.Eco1")
		(23 "Eco2.User" user "User.Eco2")
		(25 "Edge.Cuts" user "Board Geometry/Outline")
		(27 "Margin" user)
		(31 "F.CrtYd" user "Package Geometry/Place Bound Top")
		(29 "B.CrtYd" user "Package Geometry/Place Bound Bottom")
		(35 "F.Fab" user "Ref Des/Assembly Top")
		(33 "B.Fab" user "Ref Des/Assembly Bottom")
	)
	(footprint ""
		(layer "F.Cu")
		(at 417.1315 -224.027746 180)
		(property "Reference" "R6616"
			(at 0 0 180)
			(layer "F.SilkS")
			(hide yes)
			(effects
				(font
					(size 1.27 1.27)
				)
			)
		)
		(property "Value" ""
			(at 0 0 180)
			(layer "F.Fab")
			(effects
				(font
					(size 1.27 1.27)
				)
			)
		)
		(duplicate_pad_numbers_are_jumpers no)
		(fp_line
			(start 0.7874 0.4064)
			(end -0.7874 0.4064)
			(stroke
				(width 0.1524)
				(type default)
			)
			(layer "F.SilkS")
		)
		(fp_line
			(start 0.7874 -0.4064)
			(end 0.7874 0.4064)
			(stroke
				(width 0.1524)
				(type default)
			)
			(layer "F.SilkS")
		)
		(fp_line
			(start -0.7874 0.4064)
			(end -0.7874 -0.4064)
			(stroke
				(width 0.1524)
				(type default)
			)
			(layer "F.SilkS")
		)
		(fp_line
			(start -0.7874 -0.4064)
			(end 0.7874 -0.4064)
			(stroke
				(width 0.1524)
				(type default)
			)
			(layer "F.SilkS")
		)
		(fp_line
			(start 0.67945 0.3048)
			(end 0.120396 0.3048)
			(stroke
				(width 0.1)
				(type default)
			)
			(layer "F.Fab")
		)
		(fp_line
			(start 0.67945 -0.3048)
			(end 0.67945 0.3048)
			(stroke
				(width 0.1)
				(type default)
			)
			(layer "F.Fab")
		)
		(fp_line
			(start 0.12065 -0.2794)
			(end 0.12065 -0.3048)
			(stroke
				(width 0.1)
				(type default)
			)
			(layer "F.Fab")
		)
		(fp_line
			(start 0.12065 -0.3048)
			(end 0.67945 -0.3048)
			(stroke
				(width 0.1)
				(type default)
			)
			(layer "F.Fab")
		)
		(fp_line
			(start 0.120396 0.3048)
			(end 0.120396 0.2794)
			(stroke
				(width 0.1)
				(type default)
			)
			(layer "F.Fab")
		)
		(fp_line
			(start 0.120396 0.2794)
			(end -0.12065 0.2794)
			(stroke
				(width 0.1)
				(type default)
			)
			(layer "F.Fab")
		)
		(fp_line
			(start -0.12065 0.3048)
			(end -0.67945 0.3048)
			(stroke
				(width 0.1)
				(type default)
			)
			(layer "F.Fab")
		)
		(fp_line
			(start -0.12065 0.2794)
			(end -0.12065 0.3048)
			(stroke
				(width 0.1)
				(type default)
			)
			(layer "F.Fab")
		)
		(fp_line
			(start -0.12065 -0.2794)
			(end 0.12065 -0.2794)
			(stroke
				(width 0.1)
				(type default)
			)
			(layer "F.Fab")
		)
		(fp_line
			(start -0.12065 -0.305054)
			(end -0.12065 -0.2794)
			(stroke
				(width 0.1)
				(type default)
			)
			(layer "F.Fab")
		)
		(fp_line
			(start -0.67945 0.3048)
			(end -0.67945 -0.305054)
			(stroke
				(width 0.1)
				(type default)
			)
			(layer "F.Fab")
		)
		(fp_line
			(start -0.67945 -0.305054)
			(end -0.12065 -0.305054)
			(stroke
				(width 0.1)
				(type default)
			)
			(layer "F.Fab")
		)
		(pad "1" smd circle
			(at -0.40005 0 180)
			(size 0 0)
			(layers "F.Cu" "F.Mask" "F.Paste")
			(net "UART_PEX0_SDB_BUF_R_TX")
		)
		(pad "2" smd circle
			(at 0.40005 0 180)
			(size 0 0)
			(layers "F.Cu" "F.Mask" "F.Paste")
			(net "UART_PEX0_SDB_BUF_R1_TX")
		)
	)
	(footprint ""
		(layer "F.Cu")
		(at 138.985244 -98.100642)
		(property "Reference" "R1614"
			(at 0 0 0)
			(layer "F.SilkS")
			(hide yes)
			(effects
				(font
					(size 1.27 1.27)
				)
			)
		)
		(property "Value" ""
			(at 0 0 0)
			(layer "F.Fab")
			(effects
				(font
					(size 1.27 1.27)
				)
			)
		)
		(duplicate_pad_numbers_are_jumpers no)
		(fp_line
			(start -0.7874 -0.4064)
			(end 0.7874 -0.4064)
			(stroke
				(width 0.1524)
				(type default)
			)
			(layer "F.SilkS")
		)
		(fp_line
			(start -0.7874 0.4064)
			(end -0.7874 -0.4064)
			(stroke
				(width 0.1524)
				(type default)
			)
			(layer "F.SilkS")
		)
		(fp_line
			(start 0.7874 -0.4064)
			(end 0.7874 0.4064)
			(stroke
				(width 0.1524)
				(type default)
			)
			(layer "F.SilkS")
		)
		(fp_line
			(start 0.7874 0.4064)
			(end -0.7874 0.4064)
			(stroke
				(width 0.1524)
				(type default)
			)
			(layer "F.SilkS")
		)
		(fp_line
			(start -0.67945 -0.305054)
			(end -0.12065 -0.305054)
			(stroke
				(width 0.1)
				(type default)
			)
			(layer "F.Fab")
		)
		(fp_line
			(start -0.67945 0.3048)
			(end -0.67945 -0.305054)
			(stroke
				(width 0.1)
				(type default)
			)
			(layer "F.Fab")
		)
		(fp_line
			(start -0.12065 -0.305054)
			(end -0.12065 -0.2794)
			(stroke
				(width 0.1)
				(type default)
			)
			(layer "F.Fab")
		)
		(fp_line
			(start -0.12065 -0.2794)
			(end 0.12065 -0.2794)
			(stroke
				(width 0.1)
				(type default)
			)
			(layer "F.Fab")
		)
		(fp_line
			(start -0.12065 0.2794)
			(end -0.12065 0.3048)
			(stroke
				(width 0.1)
				(type default)
			)
			(layer "F.Fab")
		)
		(fp_line
			(start -0.12065 0.3048)
			(end -0.67945 0.3048)
			(stroke
				(width 0.1)
				(type default)
			)
			(layer "F.Fab")
		)
		(fp_line
			(start 0.120396 0.2794)
			(end -0.12065 0.2794)
			(stroke
				(width 0.1)
				(type default)
			)
			(layer "F.Fab")
		)
		(fp_line
			(start 0.120396 0.3048)
			(end 0.120396 0.2794)
			(stroke
				(width 0.1)
				(type default)
			)
			(layer "F.Fab")
		)
		(fp_line
			(start 0.12065 -0.3048)
			(end 0.67945 -0.3048)
			(stroke
				(width 0.1)
				(type default)
			)
			(layer "F.Fab")
		)
		(fp_line
			(start 0.12065 -0.2794)
			(end 0.12065 -0.3048)
			(stroke
				(width 0.1)
				(type default)
			)
			(layer "F.Fab")
		)
		(fp_line
			(start 0.67945 -0.3048)
			(end 0.67945 0.3048)
			(stroke
				(width 0.1)
				(type default)
			)
			(layer "F.Fab")
		)
		(fp_line
			(start 0.67945 0.3048)
			(end 0.120396 0.3048)
			(stroke
				(width 0.1)
				(type default)
			)
			(layer "F.Fab")
		)
		(pad "1" smd circle
			(at -0.40005 0)
			(size 0 0)
			(layers "F.Cu" "F.Mask" "F.Paste")
			(net "SMB_BIC_I2C9_SSD_MUX_R_SCL")
		)
		(pad "2" smd circle
			(at 0.40005 0)
			(size 0 0)
			(layers "F.Cu" "F.Mask" "F.Paste")
			(net "SMB_BIC_I2C9_SSD_MUX1_SCL")
		)
	)
	(footprint ""
		(layer "F.Cu")
		(at 355.913436 -134.042404)
		(property "Reference" "R4453"
			(at 0 0 0)
			(layer "F.SilkS")
			(hide yes)
			(effects
				(font
					(size 1.27 1.27)
				)
			)
		)
		(property "Value" ""
			(at 0 0 0)
			(layer "F.Fab")
			(effects
				(font
					(size 1.27 1.27)
				)
			)
		)
		(duplicate_pad_numbers_are_jumpers no)
		(fp_line
			(start -0.7874 -0.4064)
			(end 0.7874 -0.4064)
			(stroke
				(width 0.1524)
				(type default)
			)
			(layer "F.SilkS")
		)
		(fp_line
			(start -0.7874 0.4064)
			(end -0.7874 -0.4064)
			(stroke
				(width 0.1524)
				(type default)
			)
			(layer "F.SilkS")
		)
		(fp_line
			(start 0.7874 -0.4064)
			(end 0.7874 0.4064)
			(stroke
				(width 0.1524)
				(type default)
			)
			(layer "F.SilkS")
		)
		(fp_line
			(start 0.7874 0.4064)
			(end -0.7874 0.4064)
			(stroke
				(width 0.1524)
				(type default)
			)
			(layer "F.SilkS")
		)
		(fp_line
			(start -0.67945 -0.305054)
			(end -0.12065 -0.305054)
			(stroke
				(width 0.1)
				(type default)
			)
			(layer "F.Fab")
		)
		(fp_line
			(start -0.67945 0.3048)
			(end -0.67945 -0.305054)
			(stroke
				(width 0.1)
				(type default)
			)
			(layer "F.Fab")
		)
		(fp_line
			(start -0.12065 -0.305054)
			(end -0.12065 -0.2794)
			(stroke
				(width 0.1)
				(type default)
			)
			(layer "F.Fab")
		)
		(fp_line
			(start -0.12065 -0.2794)
			(end 0.12065 -0.2794)
			(stroke
				(width 0.1)
				(type default)
			)
			(layer "F.Fab")
		)
		(fp_line
			(start -0.12065 0.2794)
			(end -0.12065 0.3048)
			(stroke
				(width 0.1)
				(type default)
			)
			(layer "F.Fab")
		)
		(fp_line
			(start -0.12065 0.3048)
			(end -0.67945 0.3048)
			(stroke
				(width 0.1)
				(type default)
			)
			(layer "F.Fab")
		)
		(fp_line
			(start 0.120396 0.2794)
			(end -0.12065 0.2794)
			(stroke
				(width 0.1)
				(type default)
			)
			(layer "F.Fab")
		)
		(fp_line
			(start 0.120396 0.3048)
			(end 0.120396 0.2794)
			(stroke
				(width 0.1)
				(type default)
			)
			(layer "F.Fab")
		)
		(fp_line
			(start 0.12065 -0.3048)
			(end 0.67945 -0.3048)
			(stroke
				(width 0.1)
				(type default)
			)
			(layer "F.Fab")
		)
		(fp_line
			(start 0.12065 -0.2794)
			(end 0.12065 -0.3048)
			(stroke
				(width 0.1)
				(type default)
			)
			(layer "F.Fab")
		)
		(fp_line
			(start 0.67945 -0.3048)
			(end 0.67945 0.3048)
			(stroke
				(width 0.1)
				(type default)
			)
			(layer "F.Fab")
		)
		(fp_line
			(start 0.67945 0.3048)
			(end 0.120396 0.3048)
			(stroke
				(width 0.1)
				(type default)
			)
			(layer "F.Fab")
		)
		(pad "1" smd circle
			(at -0.40005 0)
			(size 0 0)
			(layers "F.Cu" "F.Mask" "F.Paste")
			(net "HP_NIC6_EN")
		)
		(pad "2" smd circle
			(at 0.40005 0)
			(size 0 0)
			(layers "F.Cu" "F.Mask" "F.Paste")
			(net "P12V_NIC6_EN_R")
		)
	)
	(footprint ""
		(layer "F.Cu")
		(at 47.289974 -72.766682 90)
		(property "Reference" "PR6906"
			(at 0 0 90)
			(layer "F.SilkS")
			(hide yes)
			(effects
				(font
					(size 1.27 1.27)
				)
			)
		)
		(property "Value" ""
			(at 0 0 90)
			(layer "F.Fab")
			(effects
				(font
					(size 1.27 1.27)
				)
			)
		)
		(duplicate_pad_numbers_are_jumpers no)
		(fp_line
			(start 0.7874 -0.4064)
			(end 0.7874 0.4064)
			(stroke
				(width 0.1524)
				(type default)
			)
			(layer "F.SilkS")
		)
		(fp_line
			(start -0.7874 -0.4064)
			(end 0.7874 -0.4064)
			(stroke
				(width 0.1524)
				(type default)
			)
			(layer "F.SilkS")
		)
		(fp_line
			(start 0.7874 0.4064)
			(end -0.7874 0.4064)
			(stroke
				(width 0.1524)
				(type default)
			)
			(layer "F.SilkS")
		)
		(fp_line
			(start -0.7874 0.4064)
			(end -0.7874 -0.4064)
			(stroke
				(width 0.1524)
				(type default)
			)
			(layer "F.SilkS")
		)
		(fp_line
			(start -0.12065 -0.305054)
			(end -0.12065 -0.2794)
			(stroke
				(width 0.1)
				(type default)
			)
			(layer "F.Fab")
		)
		(fp_line
			(start -0.67945 -0.305054)
			(end -0.12065 -0.305054)
			(stroke
				(width 0.1)
				(type default)
			)
			(layer "F.Fab")
		)
		(fp_line
			(start 0.67945 -0.3048)
			(end 0.67945 0.3048)
			(stroke
				(width 0.1)
				(type default)
			)
			(layer "F.Fab")
		)
		(fp_line
			(start 0.12065 -0.3048)
			(end 0.67945 -0.3048)
			(stroke
				(width 0.1)
				(type default)
			)
			(layer "F.Fab")
		)
		(fp_line
			(start 0.12065 -0.2794)
			(end 0.12065 -0.3048)
			(stroke
				(width 0.1)
				(type default)
			)
			(layer "F.Fab")
		)
		(fp_line
			(start -0.12065 -0.2794)
			(end 0.12065 -0.2794)
			(stroke
				(width 0.1)
				(type default)
			)
			(layer "F.Fab")
		)
		(fp_line
			(start 0.120396 0.2794)
			(end -0.12065 0.2794)
			(stroke
				(width 0.1)
				(type default)
			)
			(layer "F.Fab")
		)
		(fp_line
			(start -0.12065 0.2794)
			(end -0.12065 0.3048)
			(stroke
				(width 0.1)
				(type default)
			)
			(layer "F.Fab")
		)
		(fp_line
			(start 0.67945 0.3048)
			(end 0.120396 0.3048)
			(stroke
				(width 0.1)
				(type default)
			)
			(layer "F.Fab")
		)
		(fp_line
			(start 0.120396 0.3048)
			(end 0.120396 0.2794)
			(stroke
				(width 0.1)
				(type default)
			)
			(layer "F.Fab")
		)
		(fp_line
			(start -0.12065 0.3048)
			(end -0.67945 0.3048)
			(stroke
				(width 0.1)
				(type default)
			)
			(layer "F.Fab")
		)
		(fp_line
			(start -0.67945 0.3048)
			(end -0.67945 -0.305054)
			(stroke
				(width 0.1)
				(type default)
			)
			(layer "F.Fab")
		)
		(pad "1" smd circle
			(at -0.40005 0 90)
			(size 0 0)
			(layers "F.Cu" "F.Mask" "F.Paste")
			(net "P12V_SSD1_CO_ILIMIT")
		)
		(pad "2" smd circle
			(at 0.40005 0 90)
			(size 0 0)
			(layers "F.Cu" "F.Mask" "F.Paste")
			(net "GND")
		)
	)
	(footprint ""
		(layer "F.Cu")
		(at 306.085494 -27.092148 -90)
		(property "Reference" "R5755"
			(at 0 0 270)
			(layer "F.SilkS")
			(hide yes)
			(effects
				(font
					(size 1.27 1.27)
				)
			)
		)
		(property "Value" ""
			(at 0 0 270)
			(layer "F.Fab")
			(effects
				(font
					(size 1.27 1.27)
				)
			)
		)
		(duplicate_pad_numbers_are_jumpers no)
		(fp_line
			(start -0.7874 0.4064)
			(end -0.7874 -0.4064)
			(stroke
				(width 0.1524)
				(type default)
			)
			(layer "F.SilkS")
		)
		(fp_line
			(start 0.7874 0.4064)
			(end -0.7874 0.4064)
			(stroke
				(width 0.1524)
				(type default)
			)
			(layer "F.SilkS")
		)
		(fp_line
			(start -0.7874 -0.4064)
			(end 0.7874 -0.4064)
			(stroke
				(width 0.1524)
				(type default)
			)
			(layer "F.SilkS")
		)
		(fp_line
			(start 0.7874 -0.4064)
			(end 0.7874 0.4064)
			(stroke
				(width 0.1524)
				(type default)
			)
			(layer "F.SilkS")
		)
		(fp_line
			(start -0.67945 0.3048)
			(end -0.67945 -0.305054)
			(stroke
				(width 0.1)
				(type default)
			)
			(layer "F.Fab")
		)
		(fp_line
			(start -0.12065 0.3048)
			(end -0.67945 0.3048)
			(stroke
				(width 0.1)
				(type default)
			)
			(layer "F.Fab")
		)
		(fp_line
			(start 0.120396 0.3048)
			(end 0.120396 0.2794)
			(stroke
				(width 0.1)
				(type default)
			)
			(layer "F.Fab")
		)
		(fp_line
			(start 0.67945 0.3048)
			(end 0.120396 0.3048)
			(stroke
				(width 0.1)
				(type default)
			)
			(layer "F.Fab")
		)
		(fp_line
			(start -0.12065 0.2794)
			(end -0.12065 0.3048)
			(stroke
				(width 0.1)
				(type default)
			)
			(layer "F.Fab")
		)
		(fp_line
			(start 0.120396 0.2794)
			(end -0.12065 0.2794)
			(stroke
				(width 0.1)
				(type default)
			)
			(layer "F.Fab")
		)
		(fp_line
			(start -0.12065 -0.2794)
			(end 0.12065 -0.2794)
			(stroke
				(width 0.1)
				(type default)
			)
			(layer "F.Fab")
		)
		(fp_line
			(start 0.12065 -0.2794)
			(end 0.12065 -0.3048)
			(stroke
				(width 0.1)
				(type default)
			)
			(layer "F.Fab")
		)
		(fp_line
			(start 0.12065 -0.3048)
			(end 0.67945 -0.3048)
			(stroke
				(width 0.1)
				(type default)
			)
			(layer "F.Fab")
		)
		(fp_line
			(start 0.67945 -0.3048)
			(end 0.67945 0.3048)
			(stroke
				(width 0.1)
				(type default)
			)
			(layer "F.Fab")
		)
		(fp_line
			(start -0.67945 -0.305054)
			(end -0.12065 -0.305054)
			(stroke
				(width 0.1)
				(type default)
			)
			(layer "F.Fab")
		)
		(fp_line
			(start -0.12065 -0.305054)
			(end -0.12065 -0.2794)
			(stroke
				(width 0.1)
				(type default)
			)
			(layer "F.Fab")
		)
		(pad "1" smd circle
			(at -0.40005 0 270)
			(size 0 0)
			(layers "F.Cu" "F.Mask" "F.Paste")
			(net "P3V3_SSD10")
		)
		(pad "2" smd circle
			(at 0.40005 0 270)
			(size 0 0)
			(layers "F.Cu" "F.Mask" "F.Paste")
			(net "SSD10_LED_ISO_N")
		)
	)
	(footprint ""
		(layer "F.Cu")
		(at 144.882616 -29.875734)
		(property "Reference" "PU124"
			(at -3.135884 -2.121662 90)
			(unlocked yes)
			(layer "F.SilkS")
			(effects
				(font
					(size 0.7874 0.5842)
					(thickness 0.1524)
				)
			)
		)
		(property "Value" ""
			(at 0 0 0)
			(layer "F.Fab")
			(effects
				(font
					(size 1.27 1.27)
				)
			)
		)
		(duplicate_pad_numbers_are_jumpers no)
		(fp_line
			(start -1.239774 -1.495298)
			(end 1.239774 -1.495298)
			(stroke
				(width 0.1524)
				(type default)
			)
			(layer "F.SilkS")
		)
		(fp_line
			(start -1.239774 1.495298)
			(end -1.239774 -1.495298)
			(stroke
				(width 0.1524)
				(type default)
			)
			(layer "F.SilkS")
		)
		(fp_line
			(start 1.239774 -1.495298)
			(end 1.239774 1.495298)
			(stroke
				(width 0.1524)
				(type default)
			)
			(layer "F.SilkS")
		)
		(fp_line
			(start 1.239774 1.495298)
			(end -1.239774 1.495298)
			(stroke
				(width 0.1524)
				(type default)
			)
			(layer "F.SilkS")
		)
		(fp_poly
			(pts
				(xy -2.222246 -1.384554) (xy -2.940812 -0.665988) (xy -1.86309 -0.306832)
			)
			(stroke
				(width 0)
				(type default)
			)
			(fill yes)
			(layer "F.SilkS")
		)
		(fp_line
			(start -0.8001 -1.050036)
			(end 0.8001 -1.050036)
			(stroke
				(width 0.1)
				(type default)
			)
			(layer "F.Fab")
		)
		(fp_line
			(start -0.8001 1.050036)
			(end -0.8001 -1.050036)
			(stroke
				(width 0.1)
				(type default)
			)
			(layer "F.Fab")
		)
		(fp_line
			(start 0.8001 -1.050036)
			(end 0.8001 1.050036)
			(stroke
				(width 0.1)
				(type default)
			)
			(layer "F.Fab")
		)
		(fp_line
			(start 0.8001 1.050036)
			(end -0.8001 1.050036)
			(stroke
				(width 0.1)
				(type default)
			)
			(layer "F.Fab")
		)
		(fp_poly
			(pts
				(xy -2.458974 -0.508) (xy -2.458974 0.508) (xy -1.442974 0)
			)
			(stroke
				(width 0)
				(type default)
			)
			(fill yes)
			(layer "F.Fab")
		)
		(pad "1_2" smd circle
			(at -0.374904 0 90)
			(size 0 0)
			(layers "F.Cu" "F.Mask" "F.Paste")
			(net "P3V3_AUX")
		)
		(pad "3" smd rect
			(at -0.499872 0.999998)
			(size 0.254 0.7112)
			(layers "F.Cu" "F.Mask" "F.Paste")
			(net "GND")
		)
		(pad "4" smd rect
			(at 0 0.999998)
			(size 0.254 0.7112)
			(layers "F.Cu" "F.Mask" "F.Paste")
			(net "P3V3_SSD5_CO_ILIMIT")
		)
		(pad "5" smd rect
			(at 0.499872 0.999998)
			(size 0.254 0.7112)
			(layers "F.Cu" "F.Mask" "F.Paste")
			(net "P3V3_SSD5_CO_MODE")
		)
		(pad "6_7" smd circle
			(at 0.374904 0 270)
			(size 0 0)
			(layers "F.Cu" "F.Mask" "F.Paste")
			(net "P3V3_SSD5")
		)
		(pad "8" smd rect
			(at 0.499872 -0.999998)
			(size 0.254 0.7112)
			(layers "F.Cu" "F.Mask" "F.Paste")
			(net "P3V3_SSD5_CO_GATE")
		)
		(pad "9" smd rect
			(at 0 -0.999998)
			(size 0.254 0.7112)
			(layers "F.Cu" "F.Mask" "F.Paste")
			(net "P3V3_SSD5_CO_EN")
		)
		(pad "10" smd rect
			(at -0.499872 -0.999998)
			(size 0.254 0.7112)
			(layers "F.Cu" "F.Mask" "F.Paste")
			(net "P3V3_SSD5_CO_DV_DT")
		)
	)
)
